(kicad_pcb
	(version 20260206)
	(generator "pcbnew")
	(generator_version "10.0")
	(general
		(thickness 1.6)
		(legacy_teardrops no)
	)
	(paper "A4")
	(title_block
		(title "01162023_DA0F0TEBIF0_F0T_Expander_BD_F_brd_V02_OCP.brd")
		(comment 1 "Grand Teton / footprints 5422-5424 of 9728")
	)
	(layers
		(0 "F.Cu" signal "TOP")
		(4 "In1.Cu" signal "GND")
		(6 "In2.Cu" signal "VCC")
		(8 "In3.Cu" signal "VCC1")
		(10 "In4.Cu" signal "GND1")
		(12 "In5.Cu" signal "IN1")
		(14 "In6.Cu" signal "GND2")
		(16 "In7.Cu" signal "IN2")
		(18 "In8.Cu" signal "GND3")
		(20 "In9.Cu" signal "IN3")
		(22 "In10.Cu" signal "GND4")
		(24 "In11.Cu" signal "IN4")
		(26 "In12.Cu" signal "GND5")
		(28 "In13.Cu" signal "IN5")
		(30 "In14.Cu" signal "GND6")
		(32 "In15.Cu" signal "IN6")
		(34 "In16.Cu" signal "GND7")
		(2 "B.Cu" signal "BOTTOM")
		(9 "F.Adhes" user "F.Adhesive")
		(11 "B.Adhes" user "B.Adhesive")
		(13 "F.Paste" user "Package Geometry/Pastemask Top")
		(15 "B.Paste" user "Package Geometry/Pastemask Bottom")
		(5 "F.SilkS" user "Ref Des/Silkscreen Top")
		(7 "B.SilkS" user "Ref Des/Silkscreen Bottom")
		(1 "F.Mask" user "Board Geometry/Soldermask Top")
		(3 "B.Mask" user "Board Geometry/Soldermask Bottom")
		(17 "Dwgs.User" user "User.Drawings")
		(19 "Cmts.User" user "User.Comments")
		(21 "Eco1.User" user "User.Eco1")
		(23 "Eco2.User" user "User.Eco2")
		(25 "Edge.Cuts" user "Board Geometry/Outline")
		(27 "Margin" user)
		(31 "F.CrtYd" user "Package Geometry/Place Bound Top")
		(29 "B.CrtYd" user "Package Geometry/Place Bound Bottom")
		(35 "F.Fab" user "Ref Des/Assembly Top")
		(33 "B.Fab" user "Ref Des/Assembly Bottom")
	)
	(footprint ""
		(layer "F.Cu")
		(at 10.180066 -386.496814 90)
		(property "Reference" "U442"
			(at -1.992376 6.412992 0)
			(unlocked yes)
			(layer "F.SilkS")
			(effects
				(font
					(size 0.7874 0.5842)
					(thickness 0.1524)
				)
				(justify left)
			)
		)
		(property "Value" ""
			(at 0 0 90)
			(layer "F.Fab")
			(effects
				(font
					(size 1.27 1.27)
				)
			)
		)
		(duplicate_pad_numbers_are_jumpers no)
		(fp_line
			(start 4.549902 -4.549902)
			(end 4.549902 -4.014724)
			(stroke
				(width 0.1524)
				(type default)
			)
			(layer "F.SilkS")
		)
		(fp_line
			(start 4.014724 -4.549902)
			(end 4.549902 -4.549902)
			(stroke
				(width 0.1524)
				(type default)
			)
			(layer "F.SilkS")
		)
		(fp_line
			(start -4.549902 -4.549902)
			(end -4.014724 -4.549902)
			(stroke
				(width 0.1524)
				(type default)
			)
			(layer "F.SilkS")
		)
		(fp_line
			(start -4.549902 -4.014724)
			(end -4.549902 -4.549902)
			(stroke
				(width 0.1524)
				(type default)
			)
			(layer "F.SilkS")
		)
		(fp_line
			(start 4.549902 4.014724)
			(end 4.549902 4.549902)
			(stroke
				(width 0.1524)
				(type default)
			)
			(layer "F.SilkS")
		)
		(fp_line
			(start 4.549902 4.549902)
			(end 4.014724 4.549902)
			(stroke
				(width 0.1524)
				(type default)
			)
			(layer "F.SilkS")
		)
		(fp_line
			(start -4.014724 4.549902)
			(end -4.549902 4.549902)
			(stroke
				(width 0.1524)
				(type default)
			)
			(layer "F.SilkS")
		)
		(fp_line
			(start -4.549902 4.549902)
			(end -4.549902 4.014724)
			(stroke
				(width 0.1524)
				(type default)
			)
			(layer "F.SilkS")
		)
		(fp_poly
			(pts
				(xy -5.134102 -4.041902) (xy -4.549902 -4.041902) (xy -4.549902 -4.626102) (xy -5.134102 -4.626102)
			)
			(stroke
				(width 0)
				(type default)
			)
			(fill yes)
			(layer "F.SilkS")
		)
		(fp_line
			(start 4.549902 -4.549902)
			(end 4.549902 4.549902)
			(stroke
				(width 0.1)
				(type default)
			)
			(layer "F.Fab")
		)
		(fp_line
			(start -4.549902 -4.549902)
			(end 4.549902 -4.549902)
			(stroke
				(width 0.1)
				(type default)
			)
			(layer "F.Fab")
		)
		(fp_line
			(start 4.549902 4.549902)
			(end -4.549902 4.549902)
			(stroke
				(width 0.1)
				(type default)
			)
			(layer "F.Fab")
		)
		(fp_line
			(start -4.549902 4.549902)
			(end -4.549902 -4.549902)
			(stroke
				(width 0.1)
				(type default)
			)
			(layer "F.Fab")
		)
		(fp_poly
			(pts
				(xy -5.134102 -4.041902) (xy -4.549902 -4.041902) (xy -4.549902 -4.626102) (xy -5.134102 -4.626102)
			)
			(stroke
				(width 0)
				(type default)
			)
			(fill yes)
			(layer "F.Fab")
		)
		(pad "1" smd circle
			(at -4.400042 -3.750056)
			(size 0 0)
			(layers "F.Cu" "F.Mask" "F.Paste")
			(net "Net_9318")
		)
		(pad "2" smd circle
			(at -4.400042 -3.24993)
			(size 0 0)
			(layers "F.Cu" "F.Mask" "F.Paste")
			(net "Net_9320")
		)
		(pad "3" smd circle
			(at -4.400042 -2.750058)
			(size 0 0)
			(layers "F.Cu" "F.Mask" "F.Paste")
			(net "Net_9301")
		)
		(pad "4" smd circle
			(at -4.400042 -2.249932)
			(size 0 0)
			(layers "F.Cu" "F.Mask" "F.Paste")
			(net "Net_9306")
		)
		(pad "5" smd circle
			(at -4.400042 -1.75006)
			(size 0 0)
			(layers "F.Cu" "F.Mask" "F.Paste")
			(net "P1V2_USB_8042")
		)
		(pad "6" smd circle
			(at -4.400042 -1.249934)
			(size 0 0)
			(layers "F.Cu" "F.Mask" "F.Paste")
			(net "Net_9311")
		)
		(pad "7" smd circle
			(at -4.400042 -0.750062)
			(size 0 0)
			(layers "F.Cu" "F.Mask" "F.Paste")
			(net "Net_9316")
		)
		(pad "8" smd circle
			(at -4.400042 -0.249936)
			(size 0 0)
			(layers "F.Cu" "F.Mask" "F.Paste")
			(net "P1V2_USB_8042")
		)
		(pad "9" smd circle
			(at -4.400042 0.249936)
			(size 0 0)
			(layers "F.Cu" "F.Mask" "F.Paste")
			(net "USB2_BIC_USB8042_DP")
		)
		(pad "10" smd circle
			(at -4.400042 0.750062)
			(size 0 0)
			(layers "F.Cu" "F.Mask" "F.Paste")
			(net "USB2_BIC_USB8042_DN")
		)
		(pad "11" smd circle
			(at -4.400042 1.249934)
			(size 0 0)
			(layers "F.Cu" "F.Mask" "F.Paste")
			(net "Net_9300")
		)
		(pad "12" smd circle
			(at -4.400042 1.75006)
			(size 0 0)
			(layers "F.Cu" "F.Mask" "F.Paste")
			(net "Net_9305")
		)
		(pad "13" smd circle
			(at -4.400042 2.249932)
			(size 0 0)
			(layers "F.Cu" "F.Mask" "F.Paste")
			(net "P1V2_USB_8042")
		)
		(pad "14" smd circle
			(at -4.400042 2.750058)
			(size 0 0)
			(layers "F.Cu" "F.Mask" "F.Paste")
			(net "Net_9310")
		)
		(pad "15" smd circle
			(at -4.400042 3.24993)
			(size 0 0)
			(layers "F.Cu" "F.Mask" "F.Paste")
			(net "Net_9315")
		)
		(pad "16" smd circle
			(at -4.400042 3.750056)
			(size 0 0)
			(layers "F.Cu" "F.Mask" "F.Paste")
			(net "P3V3_USB_8042")
		)
		(pad "17" smd circle
			(at -3.750056 4.400042 90)
			(size 0 0)
			(layers "F.Cu" "F.Mask" "F.Paste")
			(net "USB2_GPU_HMC_USB8042_DP")
		)
		(pad "18" smd circle
			(at -3.24993 4.400042 90)
			(size 0 0)
			(layers "F.Cu" "F.Mask" "F.Paste")
			(net "USB2_GPU_HMC_USB8042_DN")
		)
		(pad "19" smd circle
			(at -2.750058 4.400042 90)
			(size 0 0)
			(layers "F.Cu" "F.Mask" "F.Paste")
			(net "Net_9299")
		)
		(pad "20" smd circle
			(at -2.249932 4.400042 90)
			(size 0 0)
			(layers "F.Cu" "F.Mask" "F.Paste")
			(net "Net_9304")
		)
		(pad "21" smd circle
			(at -1.75006 4.400042 90)
			(size 0 0)
			(layers "F.Cu" "F.Mask" "F.Paste")
			(net "P1V2_USB_8042")
		)
		(pad "22" smd circle
			(at -1.249934 4.400042 90)
			(size 0 0)
			(layers "F.Cu" "F.Mask" "F.Paste")
			(net "Net_9309")
		)
		(pad "23" smd circle
			(at -0.750062 4.400042 90)
			(size 0 0)
			(layers "F.Cu" "F.Mask" "F.Paste")
			(net "Net_9314")
		)
		(pad "24" smd circle
			(at -0.249936 4.400042 90)
			(size 0 0)
			(layers "F.Cu" "F.Mask" "F.Paste")
			(net "Net_9317")
		)
		(pad "25" smd circle
			(at 0.249936 4.400042 90)
			(size 0 0)
			(layers "F.Cu" "F.Mask" "F.Paste")
			(net "Net_9319")
		)
		(pad "26" smd circle
			(at 0.750062 4.400042 90)
			(size 0 0)
			(layers "F.Cu" "F.Mask" "F.Paste")
			(net "Net_9298")
		)
		(pad "27" smd circle
			(at 1.249934 4.400042 90)
			(size 0 0)
			(layers "F.Cu" "F.Mask" "F.Paste")
			(net "Net_9303")
		)
		(pad "28" smd circle
			(at 1.75006 4.400042 90)
			(size 0 0)
			(layers "F.Cu" "F.Mask" "F.Paste")
			(net "P1V2_USB_8042")
		)
		(pad "29" smd circle
			(at 2.249932 4.400042 90)
			(size 0 0)
			(layers "F.Cu" "F.Mask" "F.Paste")
			(net "Net_9308")
		)
		(pad "30" smd circle
			(at 2.750058 4.400042 90)
			(size 0 0)
			(layers "F.Cu" "F.Mask" "F.Paste")
			(net "Net_9313")
		)
		(pad "31" smd circle
			(at 3.24993 4.400042 90)
			(size 0 0)
			(layers "F.Cu" "F.Mask" "F.Paste")
			(net "P1V2_USB_8042")
		)
		(pad "32" smd circle
			(at 3.750056 4.400042 90)
			(size 0 0)
			(layers "F.Cu" "F.Mask" "F.Paste")
			(net "Net_9322")
		)
		(pad "33" smd circle
			(at 4.400042 3.750056)
			(size 0 0)
			(layers "F.Cu" "F.Mask" "F.Paste")
			(net "BIC_USB_8042_HUB_PWRCTL3")
		)
		(pad "34" smd circle
			(at 4.400042 3.24993)
			(size 0 0)
			(layers "F.Cu" "F.Mask" "F.Paste")
			(net "P3V3_USB_8042")
		)
		(pad "35" smd circle
			(at 4.400042 2.750058)
			(size 0 0)
			(layers "F.Cu" "F.Mask" "F.Paste")
			(net "BIC_USB_8042_HUB_PWRCTL2")
		)
		(pad "36" smd circle
			(at 4.400042 2.249932)
			(size 0 0)
			(layers "F.Cu" "F.Mask" "F.Paste")
			(net "Net_9323")
		)
		(pad "37" smd circle
			(at 4.400042 1.75006)
			(size 0 0)
			(layers "F.Cu" "F.Mask" "F.Paste")
			(net "Net_9295")
		)
		(pad "38" smd circle
			(at 4.400042 1.249934)
			(size 0 0)
			(layers "F.Cu" "F.Mask" "F.Paste")
			(net "Net_9296")
		)
		(pad "39" smd circle
			(at 4.400042 0.750062)
			(size 0 0)
			(layers "F.Cu" "F.Mask" "F.Paste")
			(net "Net_9294")
		)
		(pad "40" smd circle
			(at 4.400042 0.249936)
			(size 0 0)
			(layers "F.Cu" "F.Mask" "F.Paste")
			(net "BIC_USB_8042_HUB_FULLPWRMGMTZ")
		)
		(pad "41" smd circle
			(at 4.400042 -0.249936)
			(size 0 0)
			(layers "F.Cu" "F.Mask" "F.Paste")
			(net "Net_9321")
		)
		(pad "42" smd circle
			(at 4.400042 -0.750062)
			(size 0 0)
			(layers "F.Cu" "F.Mask" "F.Paste")
			(net "BIC_USB_8042_HUB_GANGED")
		)
		(pad "43" smd circle
			(at 4.400042 -1.249934)
			(size 0 0)
			(layers "F.Cu" "F.Mask" "F.Paste")
			(net "BIC_USB_8042_HUB_OVCUR4")
		)
		(pad "44" smd circle
			(at 4.400042 -1.75006)
			(size 0 0)
			(layers "F.Cu" "F.Mask" "F.Paste")
			(net "BIC_USB_8042_HUB_OVCUR3")
		)
		(pad "45" smd circle
			(at 4.400042 -2.249932)
			(size 0 0)
			(layers "F.Cu" "F.Mask" "F.Paste")
			(net "BIC_USB_8042_HUB_HS_SUSPEND")
		)
		(pad "46" smd circle
			(at 4.400042 -2.750058)
			(size 0 0)
			(layers "F.Cu" "F.Mask" "F.Paste")
			(net "BIC_USB_8042_HUB_OVCUR1")
		)
		(pad "47" smd circle
			(at 4.400042 -3.24993)
			(size 0 0)
			(layers "F.Cu" "F.Mask" "F.Paste")
			(net "BIC_USB_8042_HUB_OVCUR2")
		)
		(pad "48" smd circle
			(at 4.400042 -3.750056)
			(size 0 0)
			(layers "F.Cu" "F.Mask" "F.Paste")
			(net "BIC_USB_8042_HUB_VBUS")
		)
		(pad "49" smd circle
			(at 3.750056 -4.400042 90)
			(size 0 0)
			(layers "F.Cu" "F.Mask" "F.Paste")
			(net "BIC_USB_8042_HUB_TEST")
		)
		(pad "50" smd circle
			(at 3.24993 -4.400042 90)
			(size 0 0)
			(layers "F.Cu" "F.Mask" "F.Paste")
			(net "BIC_USB_8042_HUB_GRSTZ")
		)
		(pad "51" smd circle
			(at 2.750058 -4.400042 90)
			(size 0 0)
			(layers "F.Cu" "F.Mask" "F.Paste")
			(net "P1V2_USB_8042")
		)
		(pad "52" smd circle
			(at 2.249932 -4.400042 90)
			(size 0 0)
			(layers "F.Cu" "F.Mask" "F.Paste")
			(net "P3V3_USB_8042")
		)
		(pad "53" smd circle
			(at 1.75006 -4.400042 90)
			(size 0 0)
			(layers "F.Cu" "F.Mask" "F.Paste")
			(net "USB2_MB_BMC_USB8042_DP")
		)
		(pad "54" smd circle
			(at 1.249934 -4.400042 90)
			(size 0 0)
			(layers "F.Cu" "F.Mask" "F.Paste")
			(net "USB2_MB_BMC_USB8042_DN")
		)
		(pad "55" smd circle
			(at 0.750062 -4.400042 90)
			(size 0 0)
			(layers "F.Cu" "F.Mask" "F.Paste")
			(net "Net_9297")
		)
		(pad "56" smd circle
			(at 0.249936 -4.400042 90)
			(size 0 0)
			(layers "F.Cu" "F.Mask" "F.Paste")
			(net "Net_9302")
		)
		(pad "57" smd circle
			(at -0.249936 -4.400042 90)
			(size 0 0)
			(layers "F.Cu" "F.Mask" "F.Paste")
			(net "P1V2_USB_8042")
		)
		(pad "58" smd circle
			(at -0.750062 -4.400042 90)
			(size 0 0)
			(layers "F.Cu" "F.Mask" "F.Paste")
			(net "Net_9307")
		)
		(pad "59" smd circle
			(at -1.249934 -4.400042 90)
			(size 0 0)
			(layers "F.Cu" "F.Mask" "F.Paste")
			(net "Net_9312")
		)
		(pad "60" smd circle
			(at -1.75006 -4.400042 90)
			(size 0 0)
			(layers "F.Cu" "F.Mask" "F.Paste")
			(net "Net_9324")
		)
		(pad "61" smd circle
			(at -2.249932 -4.400042 90)
			(size 0 0)
			(layers "F.Cu" "F.Mask" "F.Paste")
			(net "BIC_USB_8042_HUB_XOUT")
		)
		(pad "62" smd circle
			(at -2.750058 -4.400042 90)
			(size 0 0)
			(layers "F.Cu" "F.Mask" "F.Paste")
			(net "BIC_USB_8042_HUB_XIN")
		)
		(pad "63" smd circle
			(at -3.24993 -4.400042 90)
			(size 0 0)
			(layers "F.Cu" "F.Mask" "F.Paste")
			(net "P3V3_USB_8042")
		)
		(pad "64" smd circle
			(at -3.750056 -4.400042 90)
			(size 0 0)
			(layers "F.Cu" "F.Mask" "F.Paste")
			(net "BIC_USB_8042_HUB_R1")
		)
		(pad "TH" smd circle
			(at 0 0 90)
			(size 0 0)
			(layers "F.Cu" "F.Mask" "F.Paste")
			(net "GND")
		)
		(zone
			(layer "F.Cu")
			(hatch none 0.5)
			(connect_pads
				(clearance 0)
			)
			(min_thickness 0.25)
			(keepout
				(tracks not_allowed)
				(vias allowed)
				(pads allowed)
				(copperpour not_allowed)
				(footprints allowed)
			)
			(placement
				(enabled no)
				(sheetname "")
			)
			(fill
				(thermal_gap 0.5)
				(thermal_bridge_width 0.5)
				(island_removal_mode 0)
			)
			(polygon
				(pts
					(xy 14.218666 -382.458214) (xy 10.205466 -382.458214) (xy 10.205466 -383.44602)
					(arc
						(start 13.130022 -383.44602)
						(mid 13.201325 -383.475555)
						(end 13.23086 -383.546858)
					)
					(arc
						(start 13.23086 -389.44677)
						(mid 13.201325 -389.518073)
						(end 13.130022 -389.547608)
					)
					(arc
						(start 7.23011 -389.547608)
						(mid 7.158807 -389.518073)
						(end 7.129272 -389.44677)
					)
					(arc
						(start 7.129272 -383.546858)
						(mid 7.158807 -383.475555)
						(end 7.23011 -383.44602)
					)
					(xy 10.154666 -383.44602) (xy 10.180066 -383.44602) (xy 10.180066 -382.458214) (xy 10.154666 -382.458214)
					(xy 6.141466 -382.458214) (xy 6.141466 -390.535414) (xy 14.218666 -390.535414)
				)
			)
		)
	)
	(footprint ""
		(layer "F.Cu")
		(at 327.992232 -28.225242 180)
		(property "Reference" "C518"
			(at 0 0 180)
			(layer "F.SilkS")
			(hide yes)
			(effects
				(font
					(size 1.27 1.27)
				)
			)
		)
		(property "Value" ""
			(at 0 0 180)
			(layer "F.Fab")
			(effects
				(font
					(size 1.27 1.27)
				)
			)
		)
		(duplicate_pad_numbers_are_jumpers no)
		(fp_line
			(start 0.299974 0.150114)
			(end -0.299974 0.150114)
			(stroke
				(width 0.1)
				(type default)
			)
			(layer "F.Fab")
		)
		(fp_line
			(start 0.299974 -0.150114)
			(end 0.299974 0.150114)
			(stroke
				(width 0.1)
				(type default)
			)
			(layer "F.Fab")
		)
		(fp_line
			(start -0.299974 0.150114)
			(end -0.299974 -0.150114)
			(stroke
				(width 0.1)
				(type default)
			)
			(layer "F.Fab")
		)
		(fp_line
			(start -0.299974 -0.150114)
			(end 0.299974 -0.150114)
			(stroke
				(width 0.1)
				(type default)
			)
			(layer "F.Fab")
		)
		(pad "1" smd rect
			(at -0.2667 0 180)
			(size 0.3048 0.381)
			(layers "F.Cu" "F.Mask" "F.Paste")
			(net "P5E_PEX2_STN2_TX_DN<32>")
		)
		(pad "2" smd rect
			(at 0.2667 0 180)
			(size 0.3048 0.381)
			(layers "F.Cu" "F.Mask" "F.Paste")
			(net "P5E_PEX2_STN2_TX_C_DN<32>")
		)
	)
	(footprint ""
		(layer "F.Cu")
		(at 260.98246 -29.875734)
		(property "Reference" "PU128"
			(at -3.312414 -2.21742 90)
			(unlocked yes)
			(layer "F.SilkS")
			(effects
				(font
					(size 0.7874 0.5842)
					(thickness 0.1524)
				)
			)
		)
		(property "Value" ""
			(at 0 0 0)
			(layer "F.Fab")
			(effects
				(font
					(size 1.27 1.27)
				)
			)
		)
		(duplicate_pad_numbers_are_jumpers no)
		(fp_line
			(start -1.239774 -1.495298)
			(end 1.239774 -1.495298)
			(stroke
				(width 0.1524)
				(type default)
			)
			(layer "F.SilkS")
		)
		(fp_line
			(start -1.239774 1.495298)
			(end -1.239774 -1.495298)
			(stroke
				(width 0.1524)
				(type default)
			)
			(layer "F.SilkS")
		)
		(fp_line
			(start 1.239774 -1.495298)
			(end 1.239774 1.495298)
			(stroke
				(width 0.1524)
				(type default)
			)
			(layer "F.SilkS")
		)
		(fp_line
			(start 1.239774 1.495298)
			(end -1.239774 1.495298)
			(stroke
				(width 0.1524)
				(type default)
			)
			(layer "F.SilkS")
		)
		(fp_poly
			(pts
				(xy -1.923796 -1.318514) (xy -2.642108 -0.600202) (xy -1.56464 -0.241046)
			)
			(stroke
				(width 0)
				(type default)
			)
			(fill yes)
			(layer "F.SilkS")
		)
		(fp_line
			(start -0.8001 -1.050036)
			(end 0.8001 -1.050036)
			(stroke
				(width 0.1)
				(type default)
			)
			(layer "F.Fab")
		)
		(fp_line
			(start -0.8001 1.050036)
			(end -0.8001 -1.050036)
			(stroke
				(width 0.1)
				(type default)
			)
			(layer "F.Fab")
		)
		(fp_line
			(start 0.8001 -1.050036)
			(end 0.8001 1.050036)
			(stroke
				(width 0.1)
				(type default)
			)
			(layer "F.Fab")
		)
		(fp_line
			(start 0.8001 1.050036)
			(end -0.8001 1.050036)
			(stroke
				(width 0.1)
				(type default)
			)
			(layer "F.Fab")
		)
		(fp_poly
			(pts
				(xy -2.458974 -0.508) (xy -2.458974 0.508) (xy -1.442974 0)
			)
			(stroke
				(width 0)
				(type default)
			)
			(fill yes)
			(layer "F.Fab")
		)
		(pad "1_2" smd circle
			(at -0.374904 0 90)
			(size 0 0)
			(layers "F.Cu" "F.Mask" "F.Paste")
			(net "P3V3_AUX")
		)
		(pad "3" smd rect
			(at -0.499872 0.999998)
			(size 0.254 0.7112)
			(layers "F.Cu" "F.Mask" "F.Paste")
			(net "GND")
		)
		(pad "4" smd rect
			(at 0 0.999998)
			(size 0.254 0.7112)
			(layers "F.Cu" "F.Mask" "F.Paste")
			(net "P3V3_SSD9_CO_ILIMIT")
		)
		(pad "5" smd rect
			(at 0.499872 0.999998)
			(size 0.254 0.7112)
			(layers "F.Cu" "F.Mask" "F.Paste")
			(net "P3V3_SSD9_CO_MODE")
		)
		(pad "6_7" smd circle
			(at 0.374904 0 270)
			(size 0 0)
			(layers "F.Cu" "F.Mask" "F.Paste")
			(net "P3V3_SSD9")
		)
		(pad "8" smd rect
			(at 0.499872 -0.999998)
			(size 0.254 0.7112)
			(layers "F.Cu" "F.Mask" "F.Paste")
			(net "P3V3_SSD9_CO_GATE")
		)
		(pad "9" smd rect
			(at 0 -0.999998)
			(size 0.254 0.7112)
			(layers "F.Cu" "F.Mask" "F.Paste")
			(net "P3V3_SSD9_CO_EN")
		)
		(pad "10" smd rect
			(at -0.499872 -0.999998)
			(size 0.254 0.7112)
			(layers "F.Cu" "F.Mask" "F.Paste")
			(net "P3V3_SSD9_CO_DV_DT")
		)
	)
)
